# SCM (Grand Teton) — schematic netlist excerpt (pin names and nets, part order shuffled) for the footprints in the layout excerpt that follows; sources: Cadence DE-HDL packaged netlist, KiCad conversion of 12092022_DA0F0TMDCD0_F0T_Management_Board_D_brd_V3_OCP.brd

SW6  SW_PUSHBUTTON4P_12_G34_H2  SW4S_DTSAM-63N/K-S-Q-T/R MECH  pkg SW4S_DTSAM63N  page 50
  \1\  = GND
  \2\  = REAR_PWR_BTN_N
  \3\  = GND
  \4\  = GND

(kicad_pcb
	(version 20260206)
	(generator "pcbnew")
	(generator_version "10.0")
	(general
		(thickness 1.6)
		(legacy_teardrops no)
	)
	(paper "A4")
	(title_block
		(title "12092022_DA0F0TMDCD0_F0T_Management_Board_D_brd_V3_OCP.brd")
		(comment 1 "Grand Teton / footprints 128-128 of 1440")
	)
	(layers
		(0 "F.Cu" signal "TOP")
		(4 "In1.Cu" signal "GND")
		(6 "In2.Cu" signal "IN1")
		(8 "In3.Cu" signal "GND1")
		(10 "In4.Cu" signal "IN2")
		(12 "In5.Cu" signal "VCC")
		(14 "In6.Cu" signal "VCC1")
		(16 "In7.Cu" signal "IN3")
		(18 "In8.Cu" signal "GND2")
		(20 "In9.Cu" signal "IN4")
		(22 "In10.Cu" signal "GND3")
		(2 "B.Cu" signal "BOTTOM")
		(9 "F.Adhes" user "F.Adhesive")
		(11 "B.Adhes" user "B.Adhesive")
		(13 "F.Paste" user "Package Geometry/Pastemask Top")
		(15 "B.Paste" user "Package Geometry/Pastemask Bottom")
		(5 "F.SilkS" user "Ref Des/Silkscreen Top")
		(7 "B.SilkS" user "Ref Des/Silkscreen Bottom")
		(1 "F.Mask" user "Board Geometry/Soldermask Top")
		(3 "B.Mask" user "Board Geometry/Soldermask Bottom")
		(17 "Dwgs.User" user "User.Drawings")
		(19 "Cmts.User" user "User.Comments")
		(21 "Eco1.User" user "User.Eco1")
		(23 "Eco2.User" user "User.Eco2")
		(25 "Edge.Cuts" user "Board Geometry/Outline")
		(27 "Margin" user)
		(31 "F.CrtYd" user "Package Geometry/Place Bound Top")
		(29 "B.CrtYd" user "Package Geometry/Place Bound Bottom")
		(35 "F.Fab" user "Ref Des/Assembly Top")
		(33 "B.Fab" user "Ref Des/Assembly Bottom")
	)
	(footprint ""
		(layer "F.Cu")
		(at 7.999984 -2.94005)
		(property "Reference" "SW6"
			(at -1.015238 -5.161534 0)
			(unlocked yes)
			(layer "F.SilkS")
			(effects
				(font
					(size 0.7874 0.5842)
					(thickness 0.1524)
				)
				(justify left)
			)
		)
		(property "Value" ""
			(at 0 0 0)
			(layer "F.Fab")
			(effects
				(font
					(size 1.27 1.27)
				)
			)
		)
		(duplicate_pad_numbers_are_jumpers no)
		(fp_line
			(start -3.700018 -4.549902)
			(end -3.700018 -2.51206)
			(stroke
				(width 0.1524)
				(type default)
			)
			(layer "F.SilkS")
		)
		(fp_line
			(start -3.700018 -0.98806)
			(end -3.700018 -0.88646)
			(stroke
				(width 0.1524)
				(type default)
			)
			(layer "F.SilkS")
		)
		(fp_line
			(start -3.700018 1.39954)
			(end -3.700018 1.549908)
			(stroke
				(width 0.1524)
				(type default)
			)
			(layer "F.SilkS")
		)
		(fp_line
			(start -3.700018 1.549908)
			(end -1.75006 1.549908)
			(stroke
				(width 0.1524)
				(type default)
			)
			(layer "F.SilkS")
		)
		(fp_line
			(start -3.1496 -4.549902)
			(end -3.700018 -4.549902)
			(stroke
				(width 0.1524)
				(type default)
			)
			(layer "F.SilkS")
		)
		(fp_line
			(start -1.75006 1.549908)
			(end -1.75006 4.549902)
			(stroke
				(width 0.1524)
				(type default)
			)
			(layer "F.SilkS")
		)
		(fp_line
			(start -1.75006 4.549902)
			(end 1.75006 4.549902)
			(stroke
				(width 0.1524)
				(type default)
			)
			(layer "F.SilkS")
		)
		(fp_line
			(start 1.3716 -4.549902)
			(end -1.3716 -4.549902)
			(stroke
				(width 0.1524)
				(type default)
			)
			(layer "F.SilkS")
		)
		(fp_line
			(start 1.75006 1.549908)
			(end 3.700018 1.549908)
			(stroke
				(width 0.1524)
				(type default)
			)
			(layer "F.SilkS")
		)
		(fp_line
			(start 1.75006 4.549902)
			(end 1.75006 1.549908)
			(stroke
				(width 0.1524)
				(type default)
			)
			(layer "F.SilkS")
		)
		(fp_line
			(start 3.700018 -4.549902)
			(end 3.1496 -4.549902)
			(stroke
				(width 0.1524)
				(type default)
			)
			(layer "F.SilkS")
		)
		(fp_line
			(start 3.700018 -2.51206)
			(end 3.700018 -4.549902)
			(stroke
				(width 0.1524)
				(type default)
			)
			(layer "F.SilkS")
		)
		(fp_line
			(start 3.700018 -0.88646)
			(end 3.700018 -0.98806)
			(stroke
				(width 0.1524)
				(type default)
			)
			(layer "F.SilkS")
		)
		(fp_line
			(start 3.700018 1.549908)
			(end 3.700018 1.39954)
			(stroke
				(width 0.1524)
				(type default)
			)
			(layer "F.SilkS")
		)
		(fp_poly
			(pts
				(xy -3.883914 -4.043934) (xy -5.310886 -3.330448) (xy -5.310886 -4.75742)
			)
			(stroke
				(width 0)
				(type default)
			)
			(fill yes)
			(layer "F.SilkS")
		)
		(fp_line
			(start -3.700018 -4.549902)
			(end -3.700018 1.549908)
			(stroke
				(width 0.1)
				(type default)
			)
			(layer "F.Fab")
		)
		(fp_line
			(start -3.700018 1.549908)
			(end -1.75006 1.549908)
			(stroke
				(width 0.1)
				(type default)
			)
			(layer "F.Fab")
		)
		(fp_line
			(start -1.75006 1.549908)
			(end -1.75006 4.549902)
			(stroke
				(width 0.1)
				(type default)
			)
			(layer "F.Fab")
		)
		(fp_line
			(start -1.75006 4.549902)
			(end 1.75006 4.549902)
			(stroke
				(width 0.1)
				(type default)
			)
			(layer "F.Fab")
		)
		(fp_line
			(start 1.75006 1.549908)
			(end 3.700018 1.549908)
			(stroke
				(width 0.1)
				(type default)
			)
			(layer "F.Fab")
		)
		(fp_line
			(start 1.75006 4.549902)
			(end 1.75006 1.549908)
			(stroke
				(width 0.1)
				(type default)
			)
			(layer "F.Fab")
		)
		(fp_line
			(start 3.700018 -4.549902)
			(end -3.700018 -4.549902)
			(stroke
				(width 0.1)
				(type default)
			)
			(layer "F.Fab")
		)
		(fp_line
			(start 3.700018 1.549908)
			(end 3.700018 -4.549902)
			(stroke
				(width 0.1)
				(type default)
			)
			(layer "F.Fab")
		)
		(fp_poly
			(pts
				(xy -3.883914 -4.043934) (xy -5.310886 -3.330448) (xy -5.310886 -4.75742)
			)
			(stroke
				(width 0)
				(type default)
			)
			(fill yes)
			(layer "F.Fab")
		)
		(pad "" np_thru_hole circle
			(at -3.50012 -1.75006)
			(size 0.9144 0.9144)
			(drill 0.9144)
			(layers "*.Cu" "*.Mask")
			(clearance 0.381)
			(thermal_gap 0.381)
		)
		(pad "" np_thru_hole circle
			(at 3.50012 -1.75006)
			(size 0.9144 0.9144)
			(drill 0.9144)
			(layers "*.Cu" "*.Mask")
			(clearance 0.381)
			(thermal_gap 0.381)
		)
		(pad "1" smd rect
			(at -2.249932 -4.05003)
			(size 1.4986 2.0066)
			(layers "F.Cu" "F.Mask" "F.Paste")
			(net "GND")
		)
		(pad "2" smd rect
			(at 2.249932 -4.05003)
			(size 1.4986 2.0066)
			(layers "F.Cu" "F.Mask" "F.Paste")
			(net "REAR_PWR_BTN_N")
		)
		(pad "3" smd rect
			(at -4.19989 0.249936)
			(size 2.0066 2.0066)
			(layers "F.Cu" "F.Mask" "F.Paste")
			(net "GND")
		)
		(pad "4" smd rect
			(at 4.19989 0.249936)
			(size 2.0066 2.0066)
			(layers "F.Cu" "F.Mask" "F.Paste")
			(net "GND")
		)
		(zone
			(layers "F.Cu" "B.Cu" "In1.Cu" "In2.Cu" "In3.Cu" "In4.Cu" "In5.Cu" "In6.Cu"
				"In7.Cu" "In8.Cu" "In9.Cu" "In10.Cu"
			)
			(hatch none 0.5)
			(connect_pads
				(clearance 0)
			)
			(min_thickness 0.25)
			(keepout
				(tracks not_allowed)
				(vias allowed)
				(pads allowed)
				(copperpour not_allowed)
				(footprints allowed)
			)
			(placement
				(enabled no)
				(sheetname "")
			)
			(fill
				(thermal_gap 0.5)
				(thermal_bridge_width 0.5)
				(island_removal_mode 0)
			)
			(polygon
				(pts
					(arc
						(start 5.363718 -4.69011)
						(mid 3.63601 -4.69011)
						(end 5.363718 -4.69011)
					)
				)
			)
		)
		(zone
			(layers "F.Cu" "B.Cu" "In1.Cu" "In2.Cu" "In3.Cu" "In4.Cu" "In5.Cu" "In6.Cu"
				"In7.Cu" "In8.Cu" "In9.Cu" "In10.Cu"
			)
			(hatch none 0.5)
			(connect_pads
				(clearance 0)
			)
			(min_thickness 0.25)
			(keepout
				(tracks not_allowed)
				(vias allowed)
				(pads allowed)
				(copperpour not_allowed)
				(footprints allowed)
			)
			(placement
				(enabled no)
				(sheetname "")
			)
			(fill
				(thermal_gap 0.5)
				(thermal_bridge_width 0.5)
				(island_removal_mode 0)
			)
			(polygon
				(pts
					(arc
						(start 12.363704 -4.69011)
						(mid 10.636504 -4.69011)
						(end 12.363704 -4.69011)
					)
				)
			)
		)
	)
)
